# S9S_MB_2U (Grand Teton) — schematic netlist excerpt (pin names and nets, part order shuffled) for the footprints in the layout excerpt that follows; sources: Cadence DE-HDL packaged netlist, KiCad conversion of 03242023_DA0F0TMBIJ0_F0T_Motherboard_J_brd_V01_OCP.brd

C269  Q_CAP  10UF 6.3V 20% X6S  pkg C0402  page 77 : A = PVCCIN_CPU1 ; B = GND
PD113  SCHOTTKY_AC  B340A-13-F IC  pkg D2010XF  page 192 : A = GND ; C = P3V3_E1S_0_R

(kicad_pcb
	(version 20260206)
	(generator "pcbnew")
	(generator_version "10.0")
	(general
		(thickness 1.6)
		(legacy_teardrops no)
	)
	(paper "A4")
	(title_block
		(title "03242023_DA0F0TMBIJ0_F0T_Motherboard_J_brd_V01_OCP.brd")
		(comment 1 "Grand Teton / footprints 3950-3951 of 6105")
	)
	(layers
		(0 "F.Cu" signal "TOP")
		(4 "In1.Cu" signal "GND")
		(6 "In2.Cu" signal "IN1")
		(8 "In3.Cu" signal "GND1")
		(10 "In4.Cu" signal "IN2")
		(12 "In5.Cu" signal "GND2")
		(14 "In6.Cu" signal "IN3")
		(16 "In7.Cu" signal "GND3")
		(18 "In8.Cu" signal "VCC")
		(20 "In9.Cu" signal "VCC1")
		(22 "In10.Cu" signal "GND4")
		(24 "In11.Cu" signal "IN4")
		(26 "In12.Cu" signal "GND5")
		(28 "In13.Cu" signal "IN5")
		(30 "In14.Cu" signal "GND6")
		(32 "In15.Cu" signal "IN6")
		(34 "In16.Cu" signal "GND7")
		(2 "B.Cu" signal "BOTTOM")
		(9 "F.Adhes" user "F.Adhesive")
		(11 "B.Adhes" user "B.Adhesive")
		(13 "F.Paste" user "Package Geometry/Pastemask Top")
		(15 "B.Paste" user "Package Geometry/Pastemask Bottom")
		(5 "F.SilkS" user "Ref Des/Silkscreen Top")
		(7 "B.SilkS" user "Ref Des/Silkscreen Bottom")
		(1 "F.Mask" user "Board Geometry/Soldermask Top")
		(3 "B.Mask" user "Board Geometry/Soldermask Bottom")
		(17 "Dwgs.User" user "User.Drawings")
		(19 "Cmts.User" user "User.Comments")
		(21 "Eco1.User" user "User.Eco1")
		(23 "Eco2.User" user "User.Eco2")
		(25 "Edge.Cuts" user "Board Geometry/Outline")
		(27 "Margin" user)
		(31 "F.CrtYd" user "Package Geometry/Place Bound Top")
		(29 "B.CrtYd" user "Package Geometry/Place Bound Bottom")
		(35 "F.Fab" user "Ref Des/Assembly Top")
		(33 "B.Fab" user "Ref Des/Assembly Bottom")
	)
	(footprint ""
		(layer "F.Cu")
		(at 228.125782 -65.08496 180)
		(property "Reference" "PD113"
			(at 4.123944 -2.386076 0)
			(unlocked yes)
			(layer "F.SilkS")
			(effects
				(font
					(size 0.7874 0.5842)
					(thickness 0.1524)
				)
				(justify left)
			)
		)
		(property "Value" ""
			(at 0 0 180)
			(layer "F.Fab")
			(effects
				(font
					(size 1.27 1.27)
				)
			)
		)
		(duplicate_pad_numbers_are_jumpers no)
		(fp_line
			(start 4.107942 1.459992)
			(end -3.400044 1.459992)
			(stroke
				(width 0.1524)
				(type default)
			)
			(layer "F.SilkS")
		)
		(fp_line
			(start 4.107942 -1.459992)
			(end 4.107942 1.459992)
			(stroke
				(width 0.1524)
				(type default)
			)
			(layer "F.SilkS")
		)
		(fp_line
			(start -3.400044 1.459992)
			(end -3.400044 -1.459992)
			(stroke
				(width 0.1524)
				(type default)
			)
			(layer "F.SilkS")
		)
		(fp_line
			(start -3.400044 -1.459992)
			(end 4.107942 -1.459992)
			(stroke
				(width 0.1524)
				(type default)
			)
			(layer "F.SilkS")
		)
		(fp_rect
			(start 4.107942 -1.459992)
			(end 3.308096 1.459992)
			(stroke
				(width 0)
				(type default)
			)
			(fill yes)
			(layer "F.SilkS")
		)
		(fp_line
			(start 2.29997 1.459992)
			(end -2.29997 1.459992)
			(stroke
				(width 0.1)
				(type default)
			)
			(layer "F.Fab")
		)
		(fp_line
			(start 2.29997 -1.459992)
			(end 2.29997 1.459992)
			(stroke
				(width 0.1)
				(type default)
			)
			(layer "F.Fab")
		)
		(fp_line
			(start -2.29997 1.459992)
			(end -2.29997 -1.459992)
			(stroke
				(width 0.1)
				(type default)
			)
			(layer "F.Fab")
		)
		(fp_line
			(start -2.29997 -1.459992)
			(end 2.29997 -1.459992)
			(stroke
				(width 0.1)
				(type default)
			)
			(layer "F.Fab")
		)
		(fp_text user "-"
			(at 5.4102 0.29845 0)
			(unlocked yes)
			(layer "F.SilkS")
			(effects
				(font
					(size 1.905 1.4224)
					(thickness 0.1524)
				)
				(justify left)
			)
		)
		(fp_text user "+"
			(at -4.7752 -0.12065 180)
			(unlocked yes)
			(layer "F.SilkS")
			(effects
				(font
					(size 1.905 1.4224)
					(thickness 0.1524)
				)
				(justify left)
			)
		)
		(fp_text user "-"
			(at 5.4102 0.29845 0)
			(unlocked yes)
			(layer "F.Fab")
			(effects
				(font
					(size 1.905 1.4224)
					(thickness 0.1524)
				)
				(justify left)
			)
		)
		(fp_text user "+"
			(at -4.7752 -0.12065 180)
			(unlocked yes)
			(layer "F.Fab")
			(effects
				(font
					(size 1.905 1.4224)
					(thickness 0.1524)
				)
				(justify left)
			)
		)
		(pad "A" smd rect
			(at -1.999996 0 270)
			(size 1.7018 2.5146)
			(layers "F.Cu" "F.Mask" "F.Paste")
			(net "GND")
		)
		(pad "C" smd rect
			(at 1.999996 0 270)
			(size 1.7018 2.5146)
			(layers "F.Cu" "F.Mask" "F.Paste")
			(net "P3V3_E1S_0_R")
		)
	)
	(footprint ""
		(layer "F.Cu")
		(at 119.508016 -241.97691 -90)
		(property "Reference" "C269"
			(at 0 0 270)
			(layer "F.SilkS")
			(hide yes)
			(effects
				(font
					(size 1.27 1.27)
				)
			)
		)
		(property "Value" ""
			(at 0 0 270)
			(layer "F.Fab")
			(effects
				(font
					(size 1.27 1.27)
				)
			)
		)
		(duplicate_pad_numbers_are_jumpers no)
		(fp_line
			(start -0.7874 0.4064)
			(end -0.7874 -0.4064)
			(stroke
				(width 0.1524)
				(type default)
			)
			(layer "F.SilkS")
		)
		(fp_line
			(start 0.7874 0.4064)
			(end -0.7874 0.4064)
			(stroke
				(width 0.1524)
				(type default)
			)
			(layer "F.SilkS")
		)
		(fp_line
			(start -0.7874 -0.4064)
			(end 0.7874 -0.4064)
			(stroke
				(width 0.1524)
				(type default)
			)
			(layer "F.SilkS")
		)
		(fp_line
			(start 0.7874 -0.4064)
			(end 0.7874 0.4064)
			(stroke
				(width 0.1524)
				(type default)
			)
			(layer "F.SilkS")
		)
		(fp_line
			(start -0.67945 0.3048)
			(end -0.67945 -0.305054)
			(stroke
				(width 0.1)
				(type default)
			)
			(layer "F.Fab")
		)
		(fp_line
			(start -0.12065 0.3048)
			(end -0.67945 0.3048)
			(stroke
				(width 0.1)
				(type default)
			)
			(layer "F.Fab")
		)
		(fp_line
			(start 0.120396 0.3048)
			(end 0.120396 0.2794)
			(stroke
				(width 0.1)
				(type default)
			)
			(layer "F.Fab")
		)
		(fp_line
			(start 0.67945 0.3048)
			(end 0.120396 0.3048)
			(stroke
				(width 0.1)
				(type default)
			)
			(layer "F.Fab")
		)
		(fp_line
			(start -0.12065 0.2794)
			(end -0.12065 0.3048)
			(stroke
				(width 0.1)
				(type default)
			)
			(layer "F.Fab")
		)
		(fp_line
			(start 0.120396 0.2794)
			(end -0.12065 0.2794)
			(stroke
				(width 0.1)
				(type default)
			)
			(layer "F.Fab")
		)
		(fp_line
			(start -0.12065 -0.2794)
			(end 0.12065 -0.2794)
			(stroke
				(width 0.1)
				(type default)
			)
			(layer "F.Fab")
		)
		(fp_line
			(start 0.12065 -0.2794)
			(end 0.12065 -0.3048)
			(stroke
				(width 0.1)
				(type default)
			)
			(layer "F.Fab")
		)
		(fp_line
			(start 0.12065 -0.3048)
			(end 0.67945 -0.3048)
			(stroke
				(width 0.1)
				(type default)
			)
			(layer "F.Fab")
		)
		(fp_line
			(start 0.67945 -0.3048)
			(end 0.67945 0.3048)
			(stroke
				(width 0.1)
				(type default)
			)
			(layer "F.Fab")
		)
		(fp_line
			(start -0.67945 -0.305054)
			(end -0.12065 -0.305054)
			(stroke
				(width 0.1)
				(type default)
			)
			(layer "F.Fab")
		)
		(fp_line
			(start -0.12065 -0.305054)
			(end -0.12065 -0.2794)
			(stroke
				(width 0.1)
				(type default)
			)
			(layer "F.Fab")
		)
		(pad "1" smd circle
			(at -0.40005 0 270)
			(size 0 0)
			(layers "F.Cu" "F.Mask" "F.Paste")
			(net "PVCCIN_CPU1")
		)
		(pad "2" smd circle
			(at 0.40005 0 270)
			(size 0 0)
			(layers "F.Cu" "F.Mask" "F.Paste")
			(net "GND")
		)
	)
)
